# Stackup_F0T_Expander_BD_18L_3p09mm_EM-890K_VL411_Rev1_20221220.xls — Information (pcb-stackup)
| Stackup Information : |  |  |  |  |  |  |  |  |  |
| Stackup Type |  |  | Single Material |  |  |  |  |  |  |
| Project Name |  |  | F0T |  |  |  |  |  |  |
| Board Class |  |  | Expander_BD |  |  |  |  |  |  |
| Number of Layers |  |  | 18 |  |  |  |  |  |  |
| PCB Material |  |  | EM-890K |  |  |  |  |  |  |
| Copper Foil |  |  | VL411 (Roughness < 1um) |  |  |  |  |  |  |
| PCB Thickness (mm) |  |  | 3.09 |  |  |  |  |  |  |
| PCB Thickness (mil) |  |  | 121.7 |  |  |  |  |  |  |
| Aspect Ratio |  |  | 12.42 |  |  |  |  |  |  |
| Last Update |  |  | 44915 |  |  |  |  |  |  |
| Revision |  |  | 1 |  |  |  |  |  |  |
| Creator |  |  | Allen |  |  |  |  |  |  |
| Loss Requirement Table : |  |  |  |  |  |  |  |  |  |
| SDD21 @ Freq(GHz) |  | 4 | 4 | 4 | 4 | 4 | 4 | 4 | 4 |
| Requirement (db/inch) | Layer | TOP | IN1 | IN2 | IN3 | IN4 | IN5 | IN6 | BOTTOM |
|  | Loss | 0.58 | 0.35 | 0.35 | 0.35 | 0.35 | 0.35 | 0.35 | 0.58 |
| SDD21 @ Freq(GHz) |  | 8 | 8 | 8 | 8 | 8 | 8 | 8 | 8 |
| Requirement (db/inch) | Layer | TOP | IN1 | IN2 | IN3 | IN4 | IN5 | IN6 | BOTTOM |
|  | Loss | 1.05 | 0.5 | 0.5 | 0.5 | 0.5 | 0.51 | 0.5 | 1.05 |
| SDD21 @ Freq(GHz) |  | 16 | 16 | 16 | 16 | 16 | 16 | 16 | 16 |
| Requirement (db/inch) | Layer | TOP | IN1 | IN2 | IN3 | IN4 | IN5 | IN6 | BOTTOM |
|  | Loss | 1.78 | 0.7 | 0.7 | 0.7 | 0.7 | 0.7 | 0.7 | 1.78 |
| Stackup History : |  |  |  |  |  |  |  |  |  |
| Date (yyyy/mm/dd) | Revision | Notes |  |  |  |  |  |  |  |
| 44509 | 0.1 | First release |  |  |  |  |  |  |  |
| 44517 | 0.2 | Add 100 ohm diff impedance |  |  |  |  |  |  |  |
| 44545 | 0.3 | Change VIPPO from No to Yes |  |  |  |  |  |  |  |
| 44545 | 0.4 | Change design from Back drill without epoxy plug/fill to Back drill with epoxy plug/fill |  |  |  |  |  |  |  |
| 44557 | 0.5 | Change DiFF pair breakout region from 3.9/4.1/3.9 to 3.5/4/3.5 |  |  |  |  |  |  |  |
| 44741 | 0.6 | Release inner layer loss from 0.85dB/inch@16G to 0.88dB/inch@16G, inner layer loss from 0.5dB/inch to 0.51dB/inch |  |  |  |  |  |  |  |
| 44741 | 0.7 | Only release In5 layer loss from 0.85dB/inch@16G to 0.88dB/inch@16G, IN5 layer loss from 0.5dB/inch@8GHz to 0.51dB/inch@8GHz |  |  |  |  |  |  |  |
| 44785 | 0.8 | Add VIPPO process based on customer's requirement |  |  |  |  |  |  |  |
| 44903 | 0.9 | Change Material from IT-968G_RG312 to EM890K_VL411, and modify inner loss from 0.85dB/inch@16G to 0.7dB/inch@16G |  |  |  |  |  |  |  |
| 44915 | 1 | Add inner 85 ohm neck mode trace and modify the 85 ohm inner layer tolerance from 10% to 7.5% |  |  |  |  |  |  |  |
